# T6G (Grand Teton) — schematic netlist excerpt (pin names and nets, part order shuffled) for the footprints in the layout excerpt that follows; sources: Cadence DE-HDL packaged netlist, KiCad conversion of 04192023_DAF0TMB3IC0_F0TG_MB_C_brd_V02_OCP.brd

PC341_1  Q_CAP  22UF 4V 20% X6S  pkg C0805  page 215 : A = PVDDCR_SOC_P1 ; B = GND
R367  Q_RES  1K 1% CHIP  pkg 0402LF  page 161 : A = PVDD18_S5_P0 ; B = SMB_CPU0_SEC_SCL
R398  Q_RES  1K 1% CHIP  pkg 0402LF  page 27 : A = PVDD18_S5_P0 ; B = JTAG_CPU0_TDO

(kicad_pcb
	(version 20260206)
	(generator "pcbnew")
	(generator_version "10.0")
	(general
		(thickness 1.6)
		(legacy_teardrops no)
	)
	(paper "A4")
	(title_block
		(title "04192023_DAF0TMB3IC0_F0TG_MB_C_brd_V02_OCP.brd")
		(comment 1 "Grand Teton / footprints 5190-5192 of 8354")
	)
	(layers
		(0 "F.Cu" signal "TOP")
		(4 "In1.Cu" signal "GND")
		(6 "In2.Cu" signal "IN1")
		(8 "In3.Cu" signal "GND1")
		(10 "In4.Cu" signal "IN2")
		(12 "In5.Cu" signal "GND2")
		(14 "In6.Cu" signal "IN3")
		(16 "In7.Cu" signal "GND3")
		(18 "In8.Cu" signal "VCC")
		(20 "In9.Cu" signal "VCC1")
		(22 "In10.Cu" signal "GND4")
		(24 "In11.Cu" signal "IN4")
		(26 "In12.Cu" signal "GND5")
		(28 "In13.Cu" signal "IN5")
		(30 "In14.Cu" signal "GND6")
		(32 "In15.Cu" signal "IN6")
		(34 "In16.Cu" signal "GND7")
		(2 "B.Cu" signal "BOTTOM")
		(9 "F.Adhes" user "F.Adhesive")
		(11 "B.Adhes" user "B.Adhesive")
		(13 "F.Paste" user "Package Geometry/Pastemask Top")
		(15 "B.Paste" user "Package Geometry/Pastemask Bottom")
		(5 "F.SilkS" user "Ref Des/Silkscreen Top")
		(7 "B.SilkS" user "Ref Des/Silkscreen Bottom")
		(1 "F.Mask" user "Board Geometry/Soldermask Top")
		(3 "B.Mask" user "Board Geometry/Soldermask Bottom")
		(17 "Dwgs.User" user "User.Drawings")
		(19 "Cmts.User" user "User.Comments")
		(21 "Eco1.User" user "User.Eco1")
		(23 "Eco2.User" user "User.Eco2")
		(25 "Edge.Cuts" user "Board Geometry/Outline")
		(27 "Margin" user)
		(31 "F.CrtYd" user "Package Geometry/Place Bound Top")
		(29 "B.CrtYd" user "Package Geometry/Place Bound Bottom")
		(35 "F.Fab" user "Ref Des/Assembly Top")
		(33 "B.Fab" user "Ref Des/Assembly Bottom")
	)
	(footprint ""
		(layer "B.Cu")
		(at 242.443 -231.648 -90)
		(property "Reference" "R367"
			(at 0 0 90)
			(layer "B.SilkS")
			(hide yes)
			(effects
				(font
					(size 1.27 1.27)
				)
				(justify mirror)
			)
		)
		(property "Value" ""
			(at 0 0 90)
			(layer "B.Fab")
			(effects
				(font
					(size 1.27 1.27)
				)
				(justify mirror)
			)
		)
		(duplicate_pad_numbers_are_jumpers no)
		(fp_line
			(start -0.7874 0.4064)
			(end 0.7874 0.4064)
			(stroke
				(width 0.1524)
				(type default)
			)
			(layer "B.SilkS")
		)
		(fp_line
			(start 0.7874 0.4064)
			(end 0.7874 -0.4064)
			(stroke
				(width 0.1524)
				(type default)
			)
			(layer "B.SilkS")
		)
		(fp_line
			(start -0.7874 -0.4064)
			(end -0.7874 0.4064)
			(stroke
				(width 0.1524)
				(type default)
			)
			(layer "B.SilkS")
		)
		(fp_line
			(start 0.7874 -0.4064)
			(end -0.7874 -0.4064)
			(stroke
				(width 0.1524)
				(type default)
			)
			(layer "B.SilkS")
		)
		(fp_line
			(start -0.67945 0.3048)
			(end -0.120396 0.3048)
			(stroke
				(width 0.1)
				(type default)
			)
			(layer "B.Fab")
		)
		(fp_line
			(start -0.120396 0.3048)
			(end -0.120396 0.2794)
			(stroke
				(width 0.1)
				(type default)
			)
			(layer "B.Fab")
		)
		(fp_line
			(start 0.12065 0.3048)
			(end 0.67945 0.3048)
			(stroke
				(width 0.1)
				(type default)
			)
			(layer "B.Fab")
		)
		(fp_line
			(start 0.67945 0.3048)
			(end 0.67945 -0.305054)
			(stroke
				(width 0.1)
				(type default)
			)
			(layer "B.Fab")
		)
		(fp_line
			(start -0.120396 0.2794)
			(end 0.12065 0.2794)
			(stroke
				(width 0.1)
				(type default)
			)
			(layer "B.Fab")
		)
		(fp_line
			(start 0.12065 0.2794)
			(end 0.12065 0.3048)
			(stroke
				(width 0.1)
				(type default)
			)
			(layer "B.Fab")
		)
		(fp_line
			(start -0.12065 -0.2794)
			(end -0.12065 -0.3048)
			(stroke
				(width 0.1)
				(type default)
			)
			(layer "B.Fab")
		)
		(fp_line
			(start 0.12065 -0.2794)
			(end -0.12065 -0.2794)
			(stroke
				(width 0.1)
				(type default)
			)
			(layer "B.Fab")
		)
		(fp_line
			(start -0.67945 -0.3048)
			(end -0.67945 0.3048)
			(stroke
				(width 0.1)
				(type default)
			)
			(layer "B.Fab")
		)
		(fp_line
			(start -0.12065 -0.3048)
			(end -0.67945 -0.3048)
			(stroke
				(width 0.1)
				(type default)
			)
			(layer "B.Fab")
		)
		(fp_line
			(start 0.12065 -0.305054)
			(end 0.12065 -0.2794)
			(stroke
				(width 0.1)
				(type default)
			)
			(layer "B.Fab")
		)
		(fp_line
			(start 0.67945 -0.305054)
			(end 0.12065 -0.305054)
			(stroke
				(width 0.1)
				(type default)
			)
			(layer "B.Fab")
		)
		(pad "1" smd circle
			(at 0.40005 0 90)
			(size 0 0)
			(layers "B.Cu" "B.Mask" "B.Paste")
			(net "PVDD18_S5_P0")
		)
		(pad "2" smd circle
			(at -0.40005 0 90)
			(size 0 0)
			(layers "B.Cu" "B.Mask" "B.Paste")
			(net "SMB_CPU0_SEC_SCL")
		)
	)
	(footprint ""
		(layer "B.Cu")
		(at 112.611154 -180.200046 90)
		(property "Reference" "PC341_1"
			(at 0 0 90)
			(layer "B.SilkS")
			(hide yes)
			(effects
				(font
					(size 1.27 1.27)
				)
				(justify mirror)
			)
		)
		(property "Value" ""
			(at 0 0 90)
			(layer "B.Fab")
			(effects
				(font
					(size 1.27 1.27)
				)
				(justify mirror)
			)
		)
		(duplicate_pad_numbers_are_jumpers no)
		(fp_line
			(start 1.524 -0.762)
			(end -1.524 -0.762)
			(stroke
				(width 0.1524)
				(type default)
			)
			(layer "B.SilkS")
		)
		(fp_line
			(start -1.524 -0.762)
			(end -1.524 0.762)
			(stroke
				(width 0.1524)
				(type default)
			)
			(layer "B.SilkS")
		)
		(fp_line
			(start 1.524 0.762)
			(end 1.524 -0.762)
			(stroke
				(width 0.1524)
				(type default)
			)
			(layer "B.SilkS")
		)
		(fp_line
			(start -1.524 0.762)
			(end 1.524 0.762)
			(stroke
				(width 0.1524)
				(type default)
			)
			(layer "B.SilkS")
		)
		(fp_line
			(start 1.1049 -0.724916)
			(end 1.1049 0.724916)
			(stroke
				(width 0.1)
				(type default)
			)
			(layer "B.Fab")
		)
		(fp_line
			(start -1.1049 -0.724916)
			(end 1.1049 -0.724916)
			(stroke
				(width 0.1)
				(type default)
			)
			(layer "B.Fab")
		)
		(fp_line
			(start 1.1049 0.724916)
			(end -1.1049 0.724916)
			(stroke
				(width 0.1)
				(type default)
			)
			(layer "B.Fab")
		)
		(fp_line
			(start -1.1049 0.724916)
			(end -1.1049 -0.724916)
			(stroke
				(width 0.1)
				(type default)
			)
			(layer "B.Fab")
		)
		(pad "1" smd rect
			(at 0.889 0 90)
			(size 1.016 1.27)
			(layers "B.Cu" "B.Mask" "B.Paste")
			(net "PVDDCR_SOC_P1")
		)
		(pad "2" smd rect
			(at -0.889 0 90)
			(size 1.016 1.27)
			(layers "B.Cu" "B.Mask" "B.Paste")
			(net "GND")
		)
	)
	(footprint ""
		(layer "B.Cu")
		(at 376.218958 -205.101952 -90)
		(property "Reference" "R398"
			(at 0 0 90)
			(layer "B.SilkS")
			(hide yes)
			(effects
				(font
					(size 1.27 1.27)
				)
				(justify mirror)
			)
		)
		(property "Value" ""
			(at 0 0 90)
			(layer "B.Fab")
			(effects
				(font
					(size 1.27 1.27)
				)
				(justify mirror)
			)
		)
		(duplicate_pad_numbers_are_jumpers no)
		(fp_line
			(start -0.7874 0.4064)
			(end 0.7874 0.4064)
			(stroke
				(width 0.1524)
				(type default)
			)
			(layer "B.SilkS")
		)
		(fp_line
			(start 0.7874 0.4064)
			(end 0.7874 -0.4064)
			(stroke
				(width 0.1524)
				(type default)
			)
			(layer "B.SilkS")
		)
		(fp_line
			(start -0.7874 -0.4064)
			(end -0.7874 0.4064)
			(stroke
				(width 0.1524)
				(type default)
			)
			(layer "B.SilkS")
		)
		(fp_line
			(start 0.7874 -0.4064)
			(end -0.7874 -0.4064)
			(stroke
				(width 0.1524)
				(type default)
			)
			(layer "B.SilkS")
		)
		(fp_line
			(start -0.67945 0.3048)
			(end -0.120396 0.3048)
			(stroke
				(width 0.1)
				(type default)
			)
			(layer "B.Fab")
		)
		(fp_line
			(start -0.120396 0.3048)
			(end -0.120396 0.2794)
			(stroke
				(width 0.1)
				(type default)
			)
			(layer "B.Fab")
		)
		(fp_line
			(start 0.12065 0.3048)
			(end 0.67945 0.3048)
			(stroke
				(width 0.1)
				(type default)
			)
			(layer "B.Fab")
		)
		(fp_line
			(start 0.67945 0.3048)
			(end 0.67945 -0.305054)
			(stroke
				(width 0.1)
				(type default)
			)
			(layer "B.Fab")
		)
		(fp_line
			(start -0.120396 0.2794)
			(end 0.12065 0.2794)
			(stroke
				(width 0.1)
				(type default)
			)
			(layer "B.Fab")
		)
		(fp_line
			(start 0.12065 0.2794)
			(end 0.12065 0.3048)
			(stroke
				(width 0.1)
				(type default)
			)
			(layer "B.Fab")
		)
		(fp_line
			(start -0.12065 -0.2794)
			(end -0.12065 -0.3048)
			(stroke
				(width 0.1)
				(type default)
			)
			(layer "B.Fab")
		)
		(fp_line
			(start 0.12065 -0.2794)
			(end -0.12065 -0.2794)
			(stroke
				(width 0.1)
				(type default)
			)
			(layer "B.Fab")
		)
		(fp_line
			(start -0.67945 -0.3048)
			(end -0.67945 0.3048)
			(stroke
				(width 0.1)
				(type default)
			)
			(layer "B.Fab")
		)
		(fp_line
			(start -0.12065 -0.3048)
			(end -0.67945 -0.3048)
			(stroke
				(width 0.1)
				(type default)
			)
			(layer "B.Fab")
		)
		(fp_line
			(start 0.12065 -0.305054)
			(end 0.12065 -0.2794)
			(stroke
				(width 0.1)
				(type default)
			)
			(layer "B.Fab")
		)
		(fp_line
			(start 0.67945 -0.305054)
			(end 0.12065 -0.305054)
			(stroke
				(width 0.1)
				(type default)
			)
			(layer "B.Fab")
		)
		(pad "1" smd circle
			(at 0.40005 0 90)
			(size 0 0)
			(layers "B.Cu" "B.Mask" "B.Paste")
			(net "PVDD18_S5_P0")
		)
		(pad "2" smd circle
			(at -0.40005 0 90)
			(size 0 0)
			(layers "B.Cu" "B.Mask" "B.Paste")
			(net "JTAG_CPU0_TDO")
		)
	)
)
